(kicad_pcb
	(version 20260206)
	(generator "pcbnew")
	(generator_version "10.0")
	(general
		(thickness 1.6)
		(legacy_teardrops no)
	)
	(paper "A4")
	(title_block
		(title "01162023_DA0F0TEBIF0_F0T_Expander_BD_F_brd_V02_OCP.brd")
		(comment 1 "Grand Teton / footprints 2767-2773 of 9728")
	)
	(layers
		(0 "F.Cu" signal "TOP")
		(4 "In1.Cu" signal "GND")
		(6 "In2.Cu" signal "VCC")
		(8 "In3.Cu" signal "VCC1")
		(10 "In4.Cu" signal "GND1")
		(12 "In5.Cu" signal "IN1")
		(14 "In6.Cu" signal "GND2")
		(16 "In7.Cu" signal "IN2")
		(18 "In8.Cu" signal "GND3")
		(20 "In9.Cu" signal "IN3")
		(22 "In10.Cu" signal "GND4")
		(24 "In11.Cu" signal "IN4")
		(26 "In12.Cu" signal "GND5")
		(28 "In13.Cu" signal "IN5")
		(30 "In14.Cu" signal "GND6")
		(32 "In15.Cu" signal "IN6")
		(34 "In16.Cu" signal "GND7")
		(2 "B.Cu" signal "BOTTOM")
		(9 "F.Adhes" user "F.Adhesive")
		(11 "B.Adhes" user "B.Adhesive")
		(13 "F.Paste" user "Package Geometry/Pastemask Top")
		(15 "B.Paste" user "Package Geometry/Pastemask Bottom")
		(5 "F.SilkS" user "Ref Des/Silkscreen Top")
		(7 "B.SilkS" user "Ref Des/Silkscreen Bottom")
		(1 "F.Mask" user "Board Geometry/Soldermask Top")
		(3 "B.Mask" user "Board Geometry/Soldermask Bottom")
		(17 "Dwgs.User" user "User.Drawings")
		(19 "Cmts.User" user "User.Comments")
		(21 "Eco1.User" user "User.Eco1")
		(23 "Eco2.User" user "User.Eco2")
		(25 "Edge.Cuts" user "Board Geometry/Outline")
		(27 "Margin" user)
		(31 "F.CrtYd" user "Package Geometry/Place Bound Top")
		(29 "B.CrtYd" user "Package Geometry/Place Bound Bottom")
		(35 "F.Fab" user "Ref Des/Assembly Top")
		(33 "B.Fab" user "Ref Des/Assembly Bottom")
	)
	(footprint ""
		(layer "F.Cu")
		(at 270.960342 -117.7544 180)
		(property "Reference" "R209"
			(at 0 0 180)
			(layer "F.SilkS")
			(hide yes)
			(effects
				(font
					(size 1.27 1.27)
				)
			)
		)
		(property "Value" ""
			(at 0 0 180)
			(layer "F.Fab")
			(effects
				(font
					(size 1.27 1.27)
				)
			)
		)
		(duplicate_pad_numbers_are_jumpers no)
		(fp_line
			(start 0.7874 0.4064)
			(end -0.7874 0.4064)
			(stroke
				(width 0.1524)
				(type default)
			)
			(layer "F.SilkS")
		)
		(fp_line
			(start 0.7874 -0.4064)
			(end 0.7874 0.4064)
			(stroke
				(width 0.1524)
				(type default)
			)
			(layer "F.SilkS")
		)
		(fp_line
			(start -0.7874 0.4064)
			(end -0.7874 -0.4064)
			(stroke
				(width 0.1524)
				(type default)
			)
			(layer "F.SilkS")
		)
		(fp_line
			(start -0.7874 -0.4064)
			(end 0.7874 -0.4064)
			(stroke
				(width 0.1524)
				(type default)
			)
			(layer "F.SilkS")
		)
		(fp_line
			(start 0.67945 0.3048)
			(end 0.120396 0.3048)
			(stroke
				(width 0.1)
				(type default)
			)
			(layer "F.Fab")
		)
		(fp_line
			(start 0.67945 -0.3048)
			(end 0.67945 0.3048)
			(stroke
				(width 0.1)
				(type default)
			)
			(layer "F.Fab")
		)
		(fp_line
			(start 0.12065 -0.2794)
			(end 0.12065 -0.3048)
			(stroke
				(width 0.1)
				(type default)
			)
			(layer "F.Fab")
		)
		(fp_line
			(start 0.12065 -0.3048)
			(end 0.67945 -0.3048)
			(stroke
				(width 0.1)
				(type default)
			)
			(layer "F.Fab")
		)
		(fp_line
			(start 0.120396 0.3048)
			(end 0.120396 0.2794)
			(stroke
				(width 0.1)
				(type default)
			)
			(layer "F.Fab")
		)
		(fp_line
			(start 0.120396 0.2794)
			(end -0.12065 0.2794)
			(stroke
				(width 0.1)
				(type default)
			)
			(layer "F.Fab")
		)
		(fp_line
			(start -0.12065 0.3048)
			(end -0.67945 0.3048)
			(stroke
				(width 0.1)
				(type default)
			)
			(layer "F.Fab")
		)
		(fp_line
			(start -0.12065 0.2794)
			(end -0.12065 0.3048)
			(stroke
				(width 0.1)
				(type default)
			)
			(layer "F.Fab")
		)
		(fp_line
			(start -0.12065 -0.2794)
			(end 0.12065 -0.2794)
			(stroke
				(width 0.1)
				(type default)
			)
			(layer "F.Fab")
		)
		(fp_line
			(start -0.12065 -0.305054)
			(end -0.12065 -0.2794)
			(stroke
				(width 0.1)
				(type default)
			)
			(layer "F.Fab")
		)
		(fp_line
			(start -0.67945 0.3048)
			(end -0.67945 -0.305054)
			(stroke
				(width 0.1)
				(type default)
			)
			(layer "F.Fab")
		)
		(fp_line
			(start -0.67945 -0.305054)
			(end -0.12065 -0.305054)
			(stroke
				(width 0.1)
				(type default)
			)
			(layer "F.Fab")
		)
		(pad "1" smd circle
			(at -0.40005 0 180)
			(size 0 0)
			(layers "F.Cu" "F.Mask" "F.Paste")
			(net "PRSNTB0_NIC4_N")
		)
		(pad "2" smd circle
			(at 0.40005 0 180)
			(size 0 0)
			(layers "F.Cu" "F.Mask" "F.Paste")
			(net "P3V3_AUX")
		)
	)
	(footprint ""
		(layer "F.Cu")
		(at 364.790482 -91.356942)
		(property "Reference" "C2710"
			(at 0 0 0)
			(layer "F.SilkS")
			(hide yes)
			(effects
				(font
					(size 1.27 1.27)
				)
			)
		)
		(property "Value" ""
			(at 0 0 0)
			(layer "F.Fab")
			(effects
				(font
					(size 1.27 1.27)
				)
			)
		)
		(duplicate_pad_numbers_are_jumpers no)
		(fp_line
			(start -0.7874 -0.4064)
			(end 0.7874 -0.4064)
			(stroke
				(width 0.1524)
				(type default)
			)
			(layer "F.SilkS")
		)
		(fp_line
			(start -0.7874 0.4064)
			(end -0.7874 -0.4064)
			(stroke
				(width 0.1524)
				(type default)
			)
			(layer "F.SilkS")
		)
		(fp_line
			(start 0.7874 -0.4064)
			(end 0.7874 0.4064)
			(stroke
				(width 0.1524)
				(type default)
			)
			(layer "F.SilkS")
		)
		(fp_line
			(start 0.7874 0.4064)
			(end -0.7874 0.4064)
			(stroke
				(width 0.1524)
				(type default)
			)
			(layer "F.SilkS")
		)
		(fp_line
			(start -0.67945 -0.305054)
			(end -0.12065 -0.305054)
			(stroke
				(width 0.1)
				(type default)
			)
			(layer "F.Fab")
		)
		(fp_line
			(start -0.67945 0.3048)
			(end -0.67945 -0.305054)
			(stroke
				(width 0.1)
				(type default)
			)
			(layer "F.Fab")
		)
		(fp_line
			(start -0.12065 -0.305054)
			(end -0.12065 -0.2794)
			(stroke
				(width 0.1)
				(type default)
			)
			(layer "F.Fab")
		)
		(fp_line
			(start -0.12065 -0.2794)
			(end 0.12065 -0.2794)
			(stroke
				(width 0.1)
				(type default)
			)
			(layer "F.Fab")
		)
		(fp_line
			(start -0.12065 0.2794)
			(end -0.12065 0.3048)
			(stroke
				(width 0.1)
				(type default)
			)
			(layer "F.Fab")
		)
		(fp_line
			(start -0.12065 0.3048)
			(end -0.67945 0.3048)
			(stroke
				(width 0.1)
				(type default)
			)
			(layer "F.Fab")
		)
		(fp_line
			(start 0.120396 0.2794)
			(end -0.12065 0.2794)
			(stroke
				(width 0.1)
				(type default)
			)
			(layer "F.Fab")
		)
		(fp_line
			(start 0.120396 0.3048)
			(end 0.120396 0.2794)
			(stroke
				(width 0.1)
				(type default)
			)
			(layer "F.Fab")
		)
		(fp_line
			(start 0.12065 -0.3048)
			(end 0.67945 -0.3048)
			(stroke
				(width 0.1)
				(type default)
			)
			(layer "F.Fab")
		)
		(fp_line
			(start 0.12065 -0.2794)
			(end 0.12065 -0.3048)
			(stroke
				(width 0.1)
				(type default)
			)
			(layer "F.Fab")
		)
		(fp_line
			(start 0.67945 -0.3048)
			(end 0.67945 0.3048)
			(stroke
				(width 0.1)
				(type default)
			)
			(layer "F.Fab")
		)
		(fp_line
			(start 0.67945 0.3048)
			(end 0.120396 0.3048)
			(stroke
				(width 0.1)
				(type default)
			)
			(layer "F.Fab")
		)
		(pad "1" smd circle
			(at -0.40005 0)
			(size 0 0)
			(layers "F.Cu" "F.Mask" "F.Paste")
			(net "P3V3_AUX")
		)
		(pad "2" smd circle
			(at 0.40005 0)
			(size 0 0)
			(layers "F.Cu" "F.Mask" "F.Paste")
			(net "GND")
		)
	)
	(footprint ""
		(layer "F.Cu")
		(at 159.892492 -29.139642 180)
		(property "Reference" "C290"
			(at 0 0 180)
			(layer "F.SilkS")
			(hide yes)
			(effects
				(font
					(size 1.27 1.27)
				)
			)
		)
		(property "Value" ""
			(at 0 0 180)
			(layer "F.Fab")
			(effects
				(font
					(size 1.27 1.27)
				)
			)
		)
		(duplicate_pad_numbers_are_jumpers no)
		(fp_line
			(start 0.299974 0.150114)
			(end -0.299974 0.150114)
			(stroke
				(width 0.1)
				(type default)
			)
			(layer "F.Fab")
		)
		(fp_line
			(start 0.299974 -0.150114)
			(end 0.299974 0.150114)
			(stroke
				(width 0.1)
				(type default)
			)
			(layer "F.Fab")
		)
		(fp_line
			(start -0.299974 0.150114)
			(end -0.299974 -0.150114)
			(stroke
				(width 0.1)
				(type default)
			)
			(layer "F.Fab")
		)
		(fp_line
			(start -0.299974 -0.150114)
			(end 0.299974 -0.150114)
			(stroke
				(width 0.1)
				(type default)
			)
			(layer "F.Fab")
		)
		(pad "1" smd rect
			(at -0.2667 0 180)
			(size 0.3048 0.381)
			(layers "F.Cu" "F.Mask" "F.Paste")
			(net "P5E_PEX1_STN2_TX_DP<40>")
		)
		(pad "2" smd rect
			(at 0.2667 0 180)
			(size 0.3048 0.381)
			(layers "F.Cu" "F.Mask" "F.Paste")
			(net "P5E_PEX1_STN2_TX_C_DP<40>")
		)
	)
	(footprint ""
		(layer "F.Cu")
		(at 193.711576 -71.458074 -90)
		(property "Reference" "PD100"
			(at 4.300474 -2.733294 90)
			(unlocked yes)
			(layer "F.SilkS")
			(effects
				(font
					(size 0.7874 0.5842)
					(thickness 0.1524)
				)
				(justify left)
			)
		)
		(property "Value" ""
			(at 0 0 270)
			(layer "F.Fab")
			(effects
				(font
					(size 1.27 1.27)
				)
			)
		)
		(duplicate_pad_numbers_are_jumpers no)
		(fp_line
			(start -3.656584 1.970024)
			(end 4.240784 1.970024)
			(stroke
				(width 0.1524)
				(type default)
			)
			(layer "F.SilkS")
		)
		(fp_line
			(start 4.240784 1.970024)
			(end 4.240784 -1.970024)
			(stroke
				(width 0.1524)
				(type default)
			)
			(layer "F.SilkS")
		)
		(fp_line
			(start -3.656584 -1.970024)
			(end -3.656584 1.970024)
			(stroke
				(width 0.1524)
				(type default)
			)
			(layer "F.SilkS")
		)
		(fp_line
			(start 4.240784 -1.970024)
			(end -3.656584 -1.970024)
			(stroke
				(width 0.1524)
				(type default)
			)
			(layer "F.SilkS")
		)
		(fp_poly
			(pts
				(xy 3.580384 1.970024) (xy 3.580384 -1.970024) (xy 4.240784 -1.970024) (xy 4.240784 1.970024)
			)
			(stroke
				(width 0)
				(type default)
			)
			(fill yes)
			(layer "F.SilkS")
		)
		(fp_line
			(start -2.3749 1.970024)
			(end 2.3749 1.970024)
			(stroke
				(width 0.1)
				(type default)
			)
			(layer "F.Fab")
		)
		(fp_line
			(start 2.3749 1.970024)
			(end 2.3749 -1.970024)
			(stroke
				(width 0.1)
				(type default)
			)
			(layer "F.Fab")
		)
		(fp_line
			(start -2.3749 -1.970024)
			(end -2.3749 1.970024)
			(stroke
				(width 0.1)
				(type default)
			)
			(layer "F.Fab")
		)
		(fp_line
			(start 2.3749 -1.970024)
			(end -2.3749 -1.970024)
			(stroke
				(width 0.1)
				(type default)
			)
			(layer "F.Fab")
		)
		(fp_text user "+"
			(at -4.9784 -0.23495 270)
			(unlocked yes)
			(layer "F.Fab")
			(effects
				(font
					(size 1.905 1.4224)
					(thickness 0.1524)
				)
				(justify left)
			)
		)
		(fp_text user "-"
			(at 4.1656 -0.23495 270)
			(unlocked yes)
			(layer "F.Fab")
			(effects
				(font
					(size 1.905 1.4224)
					(thickness 0.1524)
				)
				(justify left)
			)
		)
		(pad "A" smd rect
			(at -2.450084 0 270)
			(size 2.159 2.2606)
			(layers "F.Cu" "F.Mask" "F.Paste")
			(net "GND")
		)
		(pad "C" smd rect
			(at 2.450084 0 270)
			(size 2.159 2.2606)
			(layers "F.Cu" "F.Mask" "F.Paste")
			(net "P12V_AUX")
		)
	)
	(footprint ""
		(layer "F.Cu")
		(at 441.501276 -55.78475 -90)
		(property "Reference" "PD123"
			(at 4.01955 2.130806 90)
			(unlocked yes)
			(layer "F.SilkS")
			(effects
				(font
					(size 0.7874 0.5842)
					(thickness 0.1524)
				)
				(justify left)
			)
		)
		(property "Value" ""
			(at 0 0 270)
			(layer "F.Fab")
			(effects
				(font
					(size 1.27 1.27)
				)
			)
		)
		(duplicate_pad_numbers_are_jumpers no)
		(fp_line
			(start -3.400044 1.459992)
			(end -3.400044 -1.459992)
			(stroke
				(width 0.1524)
				(type default)
			)
			(layer "F.SilkS")
		)
		(fp_line
			(start 4.107942 1.459992)
			(end -3.400044 1.459992)
			(stroke
				(width 0.1524)
				(type default)
			)
			(layer "F.SilkS")
		)
		(fp_line
			(start -3.400044 -1.459992)
			(end 4.107942 -1.459992)
			(stroke
				(width 0.1524)
				(type default)
			)
			(layer "F.SilkS")
		)
		(fp_line
			(start 4.107942 -1.459992)
			(end 4.107942 1.459992)
			(stroke
				(width 0.1524)
				(type default)
			)
			(layer "F.SilkS")
		)
		(fp_poly
			(pts
				(xy 4.107942 -1.459992) (xy 4.107942 1.459992) (xy 3.308096 1.459992) (xy 3.308096 -1.459992)
			)
			(stroke
				(width 0)
				(type default)
			)
			(fill yes)
			(layer "F.SilkS")
		)
		(fp_line
			(start -2.29997 1.459992)
			(end -2.29997 -1.459992)
			(stroke
				(width 0.1)
				(type default)
			)
			(layer "F.Fab")
		)
		(fp_line
			(start 2.29997 1.459992)
			(end -2.29997 1.459992)
			(stroke
				(width 0.1)
				(type default)
			)
			(layer "F.Fab")
		)
		(fp_line
			(start -2.29997 -1.459992)
			(end 2.29997 -1.459992)
			(stroke
				(width 0.1)
				(type default)
			)
			(layer "F.Fab")
		)
		(fp_line
			(start 2.29997 -1.459992)
			(end 2.29997 1.459992)
			(stroke
				(width 0.1)
				(type default)
			)
			(layer "F.Fab")
		)
		(fp_text user "-"
			(at 5.4102 0.29845 90)
			(unlocked yes)
			(layer "F.SilkS")
			(effects
				(font
					(size 1.905 1.4224)
					(thickness 0.1524)
				)
				(justify left)
			)
		)
		(fp_text user "+"
			(at -4.7752 -0.12065 270)
			(unlocked yes)
			(layer "F.SilkS")
			(effects
				(font
					(size 1.905 1.4224)
					(thickness 0.1524)
				)
				(justify left)
			)
		)
		(fp_text user "-"
			(at 5.4102 0.29845 90)
			(unlocked yes)
			(layer "F.Fab")
			(effects
				(font
					(size 1.905 1.4224)
					(thickness 0.1524)
				)
				(justify left)
			)
		)
		(fp_text user "+"
			(at -4.7752 -0.12065 270)
			(unlocked yes)
			(layer "F.Fab")
			(effects
				(font
					(size 1.905 1.4224)
					(thickness 0.1524)
				)
				(justify left)
			)
		)
		(pad "A" smd rect
			(at -1.999996 0)
			(size 1.7018 2.5146)
			(layers "F.Cu" "F.Mask" "F.Paste")
			(net "GND")
		)
		(pad "C" smd rect
			(at 1.999996 0)
			(size 1.7018 2.5146)
			(layers "F.Cu" "F.Mask" "F.Paste")
			(net "P12V_SSD15_R")
		)
	)
	(footprint ""
		(layer "F.Cu")
		(at 209.00009 -289.230816 -90)
		(property "Reference" "R3933"
			(at 0 0 270)
			(layer "F.SilkS")
			(hide yes)
			(effects
				(font
					(size 1.27 1.27)
				)
			)
		)
		(property "Value" ""
			(at 0 0 270)
			(layer "F.Fab")
			(effects
				(font
					(size 1.27 1.27)
				)
			)
		)
		(duplicate_pad_numbers_are_jumpers no)
		(fp_line
			(start -0.7874 0.4064)
			(end -0.7874 -0.4064)
			(stroke
				(width 0.1524)
				(type default)
			)
			(layer "F.SilkS")
		)
		(fp_line
			(start 0.7874 0.4064)
			(end -0.7874 0.4064)
			(stroke
				(width 0.1524)
				(type default)
			)
			(layer "F.SilkS")
		)
		(fp_line
			(start -0.7874 -0.4064)
			(end 0.7874 -0.4064)
			(stroke
				(width 0.1524)
				(type default)
			)
			(layer "F.SilkS")
		)
		(fp_line
			(start 0.7874 -0.4064)
			(end 0.7874 0.4064)
			(stroke
				(width 0.1524)
				(type default)
			)
			(layer "F.SilkS")
		)
		(fp_line
			(start -0.67945 0.3048)
			(end -0.67945 -0.305054)
			(stroke
				(width 0.1)
				(type default)
			)
			(layer "F.Fab")
		)
		(fp_line
			(start -0.12065 0.3048)
			(end -0.67945 0.3048)
			(stroke
				(width 0.1)
				(type default)
			)
			(layer "F.Fab")
		)
		(fp_line
			(start 0.120396 0.3048)
			(end 0.120396 0.2794)
			(stroke
				(width 0.1)
				(type default)
			)
			(layer "F.Fab")
		)
		(fp_line
			(start 0.67945 0.3048)
			(end 0.120396 0.3048)
			(stroke
				(width 0.1)
				(type default)
			)
			(layer "F.Fab")
		)
		(fp_line
			(start -0.12065 0.2794)
			(end -0.12065 0.3048)
			(stroke
				(width 0.1)
				(type default)
			)
			(layer "F.Fab")
		)
		(fp_line
			(start 0.120396 0.2794)
			(end -0.12065 0.2794)
			(stroke
				(width 0.1)
				(type default)
			)
			(layer "F.Fab")
		)
		(fp_line
			(start -0.12065 -0.2794)
			(end 0.12065 -0.2794)
			(stroke
				(width 0.1)
				(type default)
			)
			(layer "F.Fab")
		)
		(fp_line
			(start 0.12065 -0.2794)
			(end 0.12065 -0.3048)
			(stroke
				(width 0.1)
				(type default)
			)
			(layer "F.Fab")
		)
		(fp_line
			(start 0.12065 -0.3048)
			(end 0.67945 -0.3048)
			(stroke
				(width 0.1)
				(type default)
			)
			(layer "F.Fab")
		)
		(fp_line
			(start 0.67945 -0.3048)
			(end 0.67945 0.3048)
			(stroke
				(width 0.1)
				(type default)
			)
			(layer "F.Fab")
		)
		(fp_line
			(start -0.67945 -0.305054)
			(end -0.12065 -0.305054)
			(stroke
				(width 0.1)
				(type default)
			)
			(layer "F.Fab")
		)
		(fp_line
			(start -0.12065 -0.305054)
			(end -0.12065 -0.2794)
			(stroke
				(width 0.1)
				(type default)
			)
			(layer "F.Fab")
		)
		(pad "1" smd circle
			(at -0.40005 0 270)
			(size 0 0)
			(layers "F.Cu" "F.Mask" "F.Paste")
			(net "SMB_PEX1_HOST_LS_SCL")
		)
		(pad "2" smd circle
			(at 0.40005 0 270)
			(size 0 0)
			(layers "F.Cu" "F.Mask" "F.Paste")
			(net "P3V3_AUX")
		)
	)
	(footprint ""
		(layer "F.Cu")
		(at 272.798286 -250.070874 -90)
		(property "Reference" "R1337"
			(at 0 0 270)
			(layer "F.SilkS")
			(hide yes)
			(effects
				(font
					(size 1.27 1.27)
				)
			)
		)
		(property "Value" ""
			(at 0 0 270)
			(layer "F.Fab")
			(effects
				(font
					(size 1.27 1.27)
				)
			)
		)
		(duplicate_pad_numbers_are_jumpers no)
		(fp_line
			(start -0.7874 0.4064)
			(end -0.7874 -0.4064)
			(stroke
				(width 0.1524)
				(type default)
			)
			(layer "F.SilkS")
		)
		(fp_line
			(start 0.7874 0.4064)
			(end -0.7874 0.4064)
			(stroke
				(width 0.1524)
				(type default)
			)
			(layer "F.SilkS")
		)
		(fp_line
			(start -0.7874 -0.4064)
			(end 0.7874 -0.4064)
			(stroke
				(width 0.1524)
				(type default)
			)
			(layer "F.SilkS")
		)
		(fp_line
			(start 0.7874 -0.4064)
			(end 0.7874 0.4064)
			(stroke
				(width 0.1524)
				(type default)
			)
			(layer "F.SilkS")
		)
		(fp_line
			(start -0.67945 0.3048)
			(end -0.67945 -0.305054)
			(stroke
				(width 0.1)
				(type default)
			)
			(layer "F.Fab")
		)
		(fp_line
			(start -0.12065 0.3048)
			(end -0.67945 0.3048)
			(stroke
				(width 0.1)
				(type default)
			)
			(layer "F.Fab")
		)
		(fp_line
			(start 0.120396 0.3048)
			(end 0.120396 0.2794)
			(stroke
				(width 0.1)
				(type default)
			)
			(layer "F.Fab")
		)
		(fp_line
			(start 0.67945 0.3048)
			(end 0.120396 0.3048)
			(stroke
				(width 0.1)
				(type default)
			)
			(layer "F.Fab")
		)
		(fp_line
			(start -0.12065 0.2794)
			(end -0.12065 0.3048)
			(stroke
				(width 0.1)
				(type default)
			)
			(layer "F.Fab")
		)
		(fp_line
			(start 0.120396 0.2794)
			(end -0.12065 0.2794)
			(stroke
				(width 0.1)
				(type default)
			)
			(layer "F.Fab")
		)
		(fp_line
			(start -0.12065 -0.2794)
			(end 0.12065 -0.2794)
			(stroke
				(width 0.1)
				(type default)
			)
			(layer "F.Fab")
		)
		(fp_line
			(start 0.12065 -0.2794)
			(end 0.12065 -0.3048)
			(stroke
				(width 0.1)
				(type default)
			)
			(layer "F.Fab")
		)
		(fp_line
			(start 0.12065 -0.3048)
			(end 0.67945 -0.3048)
			(stroke
				(width 0.1)
				(type default)
			)
			(layer "F.Fab")
		)
		(fp_line
			(start 0.67945 -0.3048)
			(end 0.67945 0.3048)
			(stroke
				(width 0.1)
				(type default)
			)
			(layer "F.Fab")
		)
		(fp_line
			(start -0.67945 -0.305054)
			(end -0.12065 -0.305054)
			(stroke
				(width 0.1)
				(type default)
			)
			(layer "F.Fab")
		)
		(fp_line
			(start -0.12065 -0.305054)
			(end -0.12065 -0.2794)
			(stroke
				(width 0.1)
				(type default)
			)
			(layer "F.Fab")
		)
		(pad "1" smd circle
			(at -0.40005 0 270)
			(size 0 0)
			(layers "F.Cu" "F.Mask" "F.Paste")
			(net "PEX2_MODE_SEL1")
		)
		(pad "2" smd circle
			(at 0.40005 0 270)
			(size 0 0)
			(layers "F.Cu" "F.Mask" "F.Paste")
			(net "P1V8_PEX")
		)
	)
)
